(kicad_pcb
	(version 20260206)
	(generator "pcbnew")
	(generator_version "10.0")
	(general
		(thickness 1.6)
		(legacy_teardrops no)
	)
	(paper "A4")
	(title_block
		(title "04192023_DAF0TMB3IC0_F0TG_MB_C_brd_V02_OCP.brd")
		(comment 1 "Grand Teton / footprints 8232-8238 of 8354")
	)
	(layers
		(0 "F.Cu" signal "TOP")
		(4 "In1.Cu" signal "GND")
		(6 "In2.Cu" signal "IN1")
		(8 "In3.Cu" signal "GND1")
		(10 "In4.Cu" signal "IN2")
		(12 "In5.Cu" signal "GND2")
		(14 "In6.Cu" signal "IN3")
		(16 "In7.Cu" signal "GND3")
		(18 "In8.Cu" signal "VCC")
		(20 "In9.Cu" signal "VCC1")
		(22 "In10.Cu" signal "GND4")
		(24 "In11.Cu" signal "IN4")
		(26 "In12.Cu" signal "GND5")
		(28 "In13.Cu" signal "IN5")
		(30 "In14.Cu" signal "GND6")
		(32 "In15.Cu" signal "IN6")
		(34 "In16.Cu" signal "GND7")
		(2 "B.Cu" signal "BOTTOM")
		(9 "F.Adhes" user "F.Adhesive")
		(11 "B.Adhes" user "B.Adhesive")
		(13 "F.Paste" user "Package Geometry/Pastemask Top")
		(15 "B.Paste" user "Package Geometry/Pastemask Bottom")
		(5 "F.SilkS" user "Ref Des/Silkscreen Top")
		(7 "B.SilkS" user "Ref Des/Silkscreen Bottom")
		(1 "F.Mask" user "Board Geometry/Soldermask Top")
		(3 "B.Mask" user "Board Geometry/Soldermask Bottom")
		(17 "Dwgs.User" user "User.Drawings")
		(19 "Cmts.User" user "User.Comments")
		(21 "Eco1.User" user "User.Eco1")
		(23 "Eco2.User" user "User.Eco2")
		(25 "Edge.Cuts" user "Board Geometry/Outline")
		(27 "Margin" user)
		(31 "F.CrtYd" user "Package Geometry/Place Bound Top")
		(29 "B.CrtYd" user "Package Geometry/Place Bound Bottom")
		(35 "F.Fab" user "Ref Des/Assembly Top")
		(33 "B.Fab" user "Ref Des/Assembly Bottom")
	)
	(footprint ""
		(layer "B.Cu")
		(at 98.493834 -265.045952)
		(property "Reference" "C2108"
			(at 0 0 0)
			(layer "B.SilkS")
			(hide yes)
			(effects
				(font
					(size 1.27 1.27)
				)
				(justify mirror)
			)
		)
		(property "Value" ""
			(at 0 0 0)
			(layer "B.Fab")
			(effects
				(font
					(size 1.27 1.27)
				)
				(justify mirror)
			)
		)
		(duplicate_pad_numbers_are_jumpers no)
		(fp_line
			(start -0.7874 -0.4064)
			(end -0.7874 0.4064)
			(stroke
				(width 0.1524)
				(type default)
			)
			(layer "B.SilkS")
		)
		(fp_line
			(start -0.7874 0.4064)
			(end 0.7874 0.4064)
			(stroke
				(width 0.1524)
				(type default)
			)
			(layer "B.SilkS")
		)
		(fp_line
			(start 0.7874 -0.4064)
			(end -0.7874 -0.4064)
			(stroke
				(width 0.1524)
				(type default)
			)
			(layer "B.SilkS")
		)
		(fp_line
			(start 0.7874 0.4064)
			(end 0.7874 -0.4064)
			(stroke
				(width 0.1524)
				(type default)
			)
			(layer "B.SilkS")
		)
		(fp_line
			(start -0.67945 -0.3048)
			(end -0.67945 0.3048)
			(stroke
				(width 0.1)
				(type default)
			)
			(layer "B.Fab")
		)
		(fp_line
			(start -0.67945 0.3048)
			(end -0.120396 0.3048)
			(stroke
				(width 0.1)
				(type default)
			)
			(layer "B.Fab")
		)
		(fp_line
			(start -0.12065 -0.3048)
			(end -0.67945 -0.3048)
			(stroke
				(width 0.1)
				(type default)
			)
			(layer "B.Fab")
		)
		(fp_line
			(start -0.12065 -0.2794)
			(end -0.12065 -0.3048)
			(stroke
				(width 0.1)
				(type default)
			)
			(layer "B.Fab")
		)
		(fp_line
			(start -0.120396 0.2794)
			(end 0.12065 0.2794)
			(stroke
				(width 0.1)
				(type default)
			)
			(layer "B.Fab")
		)
		(fp_line
			(start -0.120396 0.3048)
			(end -0.120396 0.2794)
			(stroke
				(width 0.1)
				(type default)
			)
			(layer "B.Fab")
		)
		(fp_line
			(start 0.12065 -0.305054)
			(end 0.12065 -0.2794)
			(stroke
				(width 0.1)
				(type default)
			)
			(layer "B.Fab")
		)
		(fp_line
			(start 0.12065 -0.2794)
			(end -0.12065 -0.2794)
			(stroke
				(width 0.1)
				(type default)
			)
			(layer "B.Fab")
		)
		(fp_line
			(start 0.12065 0.2794)
			(end 0.12065 0.3048)
			(stroke
				(width 0.1)
				(type default)
			)
			(layer "B.Fab")
		)
		(fp_line
			(start 0.12065 0.3048)
			(end 0.67945 0.3048)
			(stroke
				(width 0.1)
				(type default)
			)
			(layer "B.Fab")
		)
		(fp_line
			(start 0.67945 -0.305054)
			(end 0.12065 -0.305054)
			(stroke
				(width 0.1)
				(type default)
			)
			(layer "B.Fab")
		)
		(fp_line
			(start 0.67945 0.3048)
			(end 0.67945 -0.305054)
			(stroke
				(width 0.1)
				(type default)
			)
			(layer "B.Fab")
		)
		(pad "1" smd circle
			(at 0.40005 0 180)
			(size 0 0)
			(layers "B.Cu" "B.Mask" "B.Paste")
			(net "PVDDIO_P1")
		)
		(pad "2" smd circle
			(at -0.40005 0 180)
			(size 0 0)
			(layers "B.Cu" "B.Mask" "B.Paste")
			(net "GND")
		)
	)
	(footprint ""
		(layer "B.Cu")
		(at 132.491226 -390.560052 90)
		(property "Reference" "C482"
			(at 0 0 90)
			(layer "B.SilkS")
			(hide yes)
			(effects
				(font
					(size 1.27 1.27)
				)
				(justify mirror)
			)
		)
		(property "Value" ""
			(at 0 0 90)
			(layer "B.Fab")
			(effects
				(font
					(size 1.27 1.27)
				)
				(justify mirror)
			)
		)
		(duplicate_pad_numbers_are_jumpers no)
		(fp_line
			(start 0.7874 -0.4064)
			(end -0.7874 -0.4064)
			(stroke
				(width 0.1524)
				(type default)
			)
			(layer "B.SilkS")
		)
		(fp_line
			(start -0.7874 -0.4064)
			(end -0.7874 0.4064)
			(stroke
				(width 0.1524)
				(type default)
			)
			(layer "B.SilkS")
		)
		(fp_line
			(start 0.7874 0.4064)
			(end 0.7874 -0.4064)
			(stroke
				(width 0.1524)
				(type default)
			)
			(layer "B.SilkS")
		)
		(fp_line
			(start -0.7874 0.4064)
			(end 0.7874 0.4064)
			(stroke
				(width 0.1524)
				(type default)
			)
			(layer "B.SilkS")
		)
		(fp_line
			(start 0.67945 -0.305054)
			(end 0.12065 -0.305054)
			(stroke
				(width 0.1)
				(type default)
			)
			(layer "B.Fab")
		)
		(fp_line
			(start 0.12065 -0.305054)
			(end 0.12065 -0.2794)
			(stroke
				(width 0.1)
				(type default)
			)
			(layer "B.Fab")
		)
		(fp_line
			(start -0.12065 -0.3048)
			(end -0.67945 -0.3048)
			(stroke
				(width 0.1)
				(type default)
			)
			(layer "B.Fab")
		)
		(fp_line
			(start -0.67945 -0.3048)
			(end -0.67945 0.3048)
			(stroke
				(width 0.1)
				(type default)
			)
			(layer "B.Fab")
		)
		(fp_line
			(start 0.12065 -0.2794)
			(end -0.12065 -0.2794)
			(stroke
				(width 0.1)
				(type default)
			)
			(layer "B.Fab")
		)
		(fp_line
			(start -0.12065 -0.2794)
			(end -0.12065 -0.3048)
			(stroke
				(width 0.1)
				(type default)
			)
			(layer "B.Fab")
		)
		(fp_line
			(start 0.12065 0.2794)
			(end 0.12065 0.3048)
			(stroke
				(width 0.1)
				(type default)
			)
			(layer "B.Fab")
		)
		(fp_line
			(start -0.120396 0.2794)
			(end 0.12065 0.2794)
			(stroke
				(width 0.1)
				(type default)
			)
			(layer "B.Fab")
		)
		(fp_line
			(start 0.67945 0.3048)
			(end 0.67945 -0.305054)
			(stroke
				(width 0.1)
				(type default)
			)
			(layer "B.Fab")
		)
		(fp_line
			(start 0.12065 0.3048)
			(end 0.67945 0.3048)
			(stroke
				(width 0.1)
				(type default)
			)
			(layer "B.Fab")
		)
		(fp_line
			(start -0.120396 0.3048)
			(end -0.120396 0.2794)
			(stroke
				(width 0.1)
				(type default)
			)
			(layer "B.Fab")
		)
		(fp_line
			(start -0.67945 0.3048)
			(end -0.120396 0.3048)
			(stroke
				(width 0.1)
				(type default)
			)
			(layer "B.Fab")
		)
		(pad "1" smd circle
			(at 0.40005 0 270)
			(size 0 0)
			(layers "B.Cu" "B.Mask" "B.Paste")
			(net "P0V9_CPU1_RT3_2A")
		)
		(pad "2" smd circle
			(at -0.40005 0 270)
			(size 0 0)
			(layers "B.Cu" "B.Mask" "B.Paste")
			(net "GND")
		)
	)
	(footprint ""
		(layer "B.Cu")
		(at 187.815728 -194.885564 180)
		(property "Reference" "R776"
			(at 0 0 0)
			(layer "B.SilkS")
			(hide yes)
			(effects
				(font
					(size 1.27 1.27)
				)
				(justify mirror)
			)
		)
		(property "Value" ""
			(at 0 0 0)
			(layer "B.Fab")
			(effects
				(font
					(size 1.27 1.27)
				)
				(justify mirror)
			)
		)
		(duplicate_pad_numbers_are_jumpers no)
		(fp_line
			(start 0.7874 0.4064)
			(end 0.7874 -0.4064)
			(stroke
				(width 0.1524)
				(type default)
			)
			(layer "B.SilkS")
		)
		(fp_line
			(start 0.7874 -0.4064)
			(end -0.7874 -0.4064)
			(stroke
				(width 0.1524)
				(type default)
			)
			(layer "B.SilkS")
		)
		(fp_line
			(start -0.7874 0.4064)
			(end 0.7874 0.4064)
			(stroke
				(width 0.1524)
				(type default)
			)
			(layer "B.SilkS")
		)
		(fp_line
			(start -0.7874 -0.4064)
			(end -0.7874 0.4064)
			(stroke
				(width 0.1524)
				(type default)
			)
			(layer "B.SilkS")
		)
		(fp_line
			(start 0.67945 0.3048)
			(end 0.67945 -0.305054)
			(stroke
				(width 0.1)
				(type default)
			)
			(layer "B.Fab")
		)
		(fp_line
			(start 0.67945 -0.305054)
			(end 0.12065 -0.305054)
			(stroke
				(width 0.1)
				(type default)
			)
			(layer "B.Fab")
		)
		(fp_line
			(start 0.12065 0.3048)
			(end 0.67945 0.3048)
			(stroke
				(width 0.1)
				(type default)
			)
			(layer "B.Fab")
		)
		(fp_line
			(start 0.12065 0.2794)
			(end 0.12065 0.3048)
			(stroke
				(width 0.1)
				(type default)
			)
			(layer "B.Fab")
		)
		(fp_line
			(start 0.12065 -0.2794)
			(end -0.12065 -0.2794)
			(stroke
				(width 0.1)
				(type default)
			)
			(layer "B.Fab")
		)
		(fp_line
			(start 0.12065 -0.305054)
			(end 0.12065 -0.2794)
			(stroke
				(width 0.1)
				(type default)
			)
			(layer "B.Fab")
		)
		(fp_line
			(start -0.120396 0.3048)
			(end -0.120396 0.2794)
			(stroke
				(width 0.1)
				(type default)
			)
			(layer "B.Fab")
		)
		(fp_line
			(start -0.120396 0.2794)
			(end 0.12065 0.2794)
			(stroke
				(width 0.1)
				(type default)
			)
			(layer "B.Fab")
		)
		(fp_line
			(start -0.12065 -0.2794)
			(end -0.12065 -0.3048)
			(stroke
				(width 0.1)
				(type default)
			)
			(layer "B.Fab")
		)
		(fp_line
			(start -0.12065 -0.3048)
			(end -0.67945 -0.3048)
			(stroke
				(width 0.1)
				(type default)
			)
			(layer "B.Fab")
		)
		(fp_line
			(start -0.67945 0.3048)
			(end -0.120396 0.3048)
			(stroke
				(width 0.1)
				(type default)
			)
			(layer "B.Fab")
		)
		(fp_line
			(start -0.67945 -0.3048)
			(end -0.67945 0.3048)
			(stroke
				(width 0.1)
				(type default)
			)
			(layer "B.Fab")
		)
		(pad "1" smd circle
			(at 0.40005 0)
			(size 0 0)
			(layers "B.Cu" "B.Mask" "B.Paste")
			(net "PD_CHJ_CPU1_DIMM_SAA")
		)
		(pad "2" smd circle
			(at -0.40005 0)
			(size 0 0)
			(layers "B.Cu" "B.Mask" "B.Paste")
			(net "GND")
		)
	)
	(footprint ""
		(layer "B.Cu")
		(at 380.091188 -398.942052 90)
		(property "Reference" "C995"
			(at 0 0 90)
			(layer "B.SilkS")
			(hide yes)
			(effects
				(font
					(size 1.27 1.27)
				)
				(justify mirror)
			)
		)
		(property "Value" ""
			(at 0 0 90)
			(layer "B.Fab")
			(effects
				(font
					(size 1.27 1.27)
				)
				(justify mirror)
			)
		)
		(duplicate_pad_numbers_are_jumpers no)
		(fp_line
			(start 0.7874 -0.4064)
			(end -0.7874 -0.4064)
			(stroke
				(width 0.1524)
				(type default)
			)
			(layer "B.SilkS")
		)
		(fp_line
			(start -0.7874 -0.4064)
			(end -0.7874 0.4064)
			(stroke
				(width 0.1524)
				(type default)
			)
			(layer "B.SilkS")
		)
		(fp_line
			(start 0.7874 0.4064)
			(end 0.7874 -0.4064)
			(stroke
				(width 0.1524)
				(type default)
			)
			(layer "B.SilkS")
		)
		(fp_line
			(start -0.7874 0.4064)
			(end 0.7874 0.4064)
			(stroke
				(width 0.1524)
				(type default)
			)
			(layer "B.SilkS")
		)
		(fp_line
			(start 0.67945 -0.305054)
			(end 0.12065 -0.305054)
			(stroke
				(width 0.1)
				(type default)
			)
			(layer "B.Fab")
		)
		(fp_line
			(start 0.12065 -0.305054)
			(end 0.12065 -0.2794)
			(stroke
				(width 0.1)
				(type default)
			)
			(layer "B.Fab")
		)
		(fp_line
			(start -0.12065 -0.3048)
			(end -0.67945 -0.3048)
			(stroke
				(width 0.1)
				(type default)
			)
			(layer "B.Fab")
		)
		(fp_line
			(start -0.67945 -0.3048)
			(end -0.67945 0.3048)
			(stroke
				(width 0.1)
				(type default)
			)
			(layer "B.Fab")
		)
		(fp_line
			(start 0.12065 -0.2794)
			(end -0.12065 -0.2794)
			(stroke
				(width 0.1)
				(type default)
			)
			(layer "B.Fab")
		)
		(fp_line
			(start -0.12065 -0.2794)
			(end -0.12065 -0.3048)
			(stroke
				(width 0.1)
				(type default)
			)
			(layer "B.Fab")
		)
		(fp_line
			(start 0.12065 0.2794)
			(end 0.12065 0.3048)
			(stroke
				(width 0.1)
				(type default)
			)
			(layer "B.Fab")
		)
		(fp_line
			(start -0.120396 0.2794)
			(end 0.12065 0.2794)
			(stroke
				(width 0.1)
				(type default)
			)
			(layer "B.Fab")
		)
		(fp_line
			(start 0.67945 0.3048)
			(end 0.67945 -0.305054)
			(stroke
				(width 0.1)
				(type default)
			)
			(layer "B.Fab")
		)
		(fp_line
			(start 0.12065 0.3048)
			(end 0.67945 0.3048)
			(stroke
				(width 0.1)
				(type default)
			)
			(layer "B.Fab")
		)
		(fp_line
			(start -0.120396 0.3048)
			(end -0.120396 0.2794)
			(stroke
				(width 0.1)
				(type default)
			)
			(layer "B.Fab")
		)
		(fp_line
			(start -0.67945 0.3048)
			(end -0.120396 0.3048)
			(stroke
				(width 0.1)
				(type default)
			)
			(layer "B.Fab")
		)
		(pad "1" smd circle
			(at 0.40005 0 270)
			(size 0 0)
			(layers "B.Cu" "B.Mask" "B.Paste")
			(net "P1V8_CPU0_RT3_1A")
		)
		(pad "2" smd circle
			(at -0.40005 0 270)
			(size 0 0)
			(layers "B.Cu" "B.Mask" "B.Paste")
			(net "GND")
		)
	)
	(footprint ""
		(layer "B.Cu")
		(at 230.886 -332.74)
		(property "Reference" "R6770"
			(at 0 0 0)
			(layer "B.SilkS")
			(hide yes)
			(effects
				(font
					(size 1.27 1.27)
				)
				(justify mirror)
			)
		)
		(property "Value" ""
			(at 0 0 0)
			(layer "B.Fab")
			(effects
				(font
					(size 1.27 1.27)
				)
				(justify mirror)
			)
		)
		(duplicate_pad_numbers_are_jumpers no)
		(fp_line
			(start -0.32512 -0.175006)
			(end -0.32512 0.175006)
			(stroke
				(width 0.1)
				(type default)
			)
			(layer "B.Fab")
		)
		(fp_line
			(start -0.32512 0.175006)
			(end 0.32512 0.175006)
			(stroke
				(width 0.1)
				(type default)
			)
			(layer "B.Fab")
		)
		(fp_line
			(start 0.32512 -0.175006)
			(end -0.32512 -0.175006)
			(stroke
				(width 0.1)
				(type default)
			)
			(layer "B.Fab")
		)
		(fp_line
			(start 0.32512 0.175006)
			(end 0.32512 -0.175006)
			(stroke
				(width 0.1)
				(type default)
			)
			(layer "B.Fab")
		)
		(pad "1" smd rect
			(at 0.2667 0 180)
			(size 0.3048 0.381)
			(layers "B.Cu" "B.Mask" "B.Paste")
			(net "P1V8_AUX")
		)
		(pad "2" smd rect
			(at -0.2667 0)
			(size 0.3048 0.381)
			(layers "B.Cu" "B.Mask" "B.Paste")
			(net "RT_SMB_MUX_ADDR2")
		)
	)
	(footprint ""
		(layer "B.Cu")
		(at 326.252078 -392.957558)
		(property "Reference" "L11"
			(at 0 0 0)
			(layer "B.SilkS")
			(hide yes)
			(effects
				(font
					(size 1.27 1.27)
				)
				(justify mirror)
			)
		)
		(property "Value" ""
			(at 0 0 0)
			(layer "B.Fab")
			(effects
				(font
					(size 1.27 1.27)
				)
				(justify mirror)
			)
		)
		(duplicate_pad_numbers_are_jumpers no)
		(fp_line
			(start -1.63576 -0.8128)
			(end -1.63576 0.8128)
			(stroke
				(width 0.1524)
				(type default)
			)
			(layer "B.SilkS")
		)
		(fp_line
			(start -1.63576 0.8128)
			(end 1.63576 0.8128)
			(stroke
				(width 0.1524)
				(type default)
			)
			(layer "B.SilkS")
		)
		(fp_line
			(start 1.63576 -0.8128)
			(end -1.63576 -0.8128)
			(stroke
				(width 0.1524)
				(type default)
			)
			(layer "B.SilkS")
		)
		(fp_line
			(start 1.63576 -0.8128)
			(end 1.63576 0.8128)
			(stroke
				(width 0.1524)
				(type default)
			)
			(layer "B.SilkS")
		)
		(fp_line
			(start -1.560576 -0.738632)
			(end 1.56083 -0.738632)
			(stroke
				(width 0.1)
				(type default)
			)
			(layer "B.Fab")
		)
		(fp_line
			(start -1.560576 0.7366)
			(end -1.560576 -0.738632)
			(stroke
				(width 0.1)
				(type default)
			)
			(layer "B.Fab")
		)
		(fp_line
			(start -1.524 0.7366)
			(end -1.560576 0.7366)
			(stroke
				(width 0.1)
				(type default)
			)
			(layer "B.Fab")
		)
		(fp_line
			(start 1.524 0.7366)
			(end -1.524 0.7366)
			(stroke
				(width 0.1)
				(type default)
			)
			(layer "B.Fab")
		)
		(fp_line
			(start 1.56083 -0.738632)
			(end 1.56083 0.7366)
			(stroke
				(width 0.1)
				(type default)
			)
			(layer "B.Fab")
		)
		(fp_line
			(start 1.56083 0.7366)
			(end 1.524 0.7366)
			(stroke
				(width 0.1)
				(type default)
			)
			(layer "B.Fab")
		)
		(pad "1" smd rect
			(at 0.94996 0)
			(size 1.1176 1.3716)
			(layers "B.Cu" "B.Mask" "B.Paste")
			(net "P1V8_CPU0_RT_1D")
		)
		(pad "2" smd rect
			(at -0.94996 0)
			(size 1.1176 1.3716)
			(layers "B.Cu" "B.Mask" "B.Paste")
			(net "P1V8_CPU0_RT0_1A")
		)
	)
	(footprint ""
		(layer "B.Cu")
		(at 122.496834 -272.284952)
		(property "Reference" "C2372"
			(at 0 0 0)
			(layer "B.SilkS")
			(hide yes)
			(effects
				(font
					(size 1.27 1.27)
				)
				(justify mirror)
			)
		)
		(property "Value" ""
			(at 0 0 0)
			(layer "B.Fab")
			(effects
				(font
					(size 1.27 1.27)
				)
				(justify mirror)
			)
		)
		(duplicate_pad_numbers_are_jumpers no)
		(fp_line
			(start -0.7874 -0.4064)
			(end -0.7874 0.4064)
			(stroke
				(width 0.1524)
				(type default)
			)
			(layer "B.SilkS")
		)
		(fp_line
			(start -0.7874 0.4064)
			(end 0.7874 0.4064)
			(stroke
				(width 0.1524)
				(type default)
			)
			(layer "B.SilkS")
		)
		(fp_line
			(start 0.7874 -0.4064)
			(end -0.7874 -0.4064)
			(stroke
				(width 0.1524)
				(type default)
			)
			(layer "B.SilkS")
		)
		(fp_line
			(start 0.7874 0.4064)
			(end 0.7874 -0.4064)
			(stroke
				(width 0.1524)
				(type default)
			)
			(layer "B.SilkS")
		)
		(fp_line
			(start -0.67945 -0.3048)
			(end -0.67945 0.3048)
			(stroke
				(width 0.1)
				(type default)
			)
			(layer "B.Fab")
		)
		(fp_line
			(start -0.67945 0.3048)
			(end -0.120396 0.3048)
			(stroke
				(width 0.1)
				(type default)
			)
			(layer "B.Fab")
		)
		(fp_line
			(start -0.12065 -0.3048)
			(end -0.67945 -0.3048)
			(stroke
				(width 0.1)
				(type default)
			)
			(layer "B.Fab")
		)
		(fp_line
			(start -0.12065 -0.2794)
			(end -0.12065 -0.3048)
			(stroke
				(width 0.1)
				(type default)
			)
			(layer "B.Fab")
		)
		(fp_line
			(start -0.120396 0.2794)
			(end 0.12065 0.2794)
			(stroke
				(width 0.1)
				(type default)
			)
			(layer "B.Fab")
		)
		(fp_line
			(start -0.120396 0.3048)
			(end -0.120396 0.2794)
			(stroke
				(width 0.1)
				(type default)
			)
			(layer "B.Fab")
		)
		(fp_line
			(start 0.12065 -0.305054)
			(end 0.12065 -0.2794)
			(stroke
				(width 0.1)
				(type default)
			)
			(layer "B.Fab")
		)
		(fp_line
			(start 0.12065 -0.2794)
			(end -0.12065 -0.2794)
			(stroke
				(width 0.1)
				(type default)
			)
			(layer "B.Fab")
		)
		(fp_line
			(start 0.12065 0.2794)
			(end 0.12065 0.3048)
			(stroke
				(width 0.1)
				(type default)
			)
			(layer "B.Fab")
		)
		(fp_line
			(start 0.12065 0.3048)
			(end 0.67945 0.3048)
			(stroke
				(width 0.1)
				(type default)
			)
			(layer "B.Fab")
		)
		(fp_line
			(start 0.67945 -0.305054)
			(end 0.12065 -0.305054)
			(stroke
				(width 0.1)
				(type default)
			)
			(layer "B.Fab")
		)
		(fp_line
			(start 0.67945 0.3048)
			(end 0.67945 -0.305054)
			(stroke
				(width 0.1)
				(type default)
			)
			(layer "B.Fab")
		)
		(pad "1" smd circle
			(at 0.40005 0 180)
			(size 0 0)
			(layers "B.Cu" "B.Mask" "B.Paste")
			(net "PVDDCR_CPU1_P1")
		)
		(pad "2" smd circle
			(at -0.40005 0 180)
			(size 0 0)
			(layers "B.Cu" "B.Mask" "B.Paste")
			(net "GND")
		)
	)
)
